# T6G (Grand Teton) — schematic netlist excerpt (pin names and nets, part order shuffled) for the footprints in the layout excerpt that follows; sources: Cadence DE-HDL packaged netlist, KiCad conversion of 04192023_DAF0TMB3IC0_F0TG_MB_C_brd_V02_OCP.brd

R6027  Q_RES  4.7K 5% EMPTY  pkg 0402LF  page 151 : A = SGPIO_SCM_RESET_N ; B = GND
C6031  Q_CAP  1UF 25V 10% X6S  pkg C0402  page 177 : A = P1V2_CPU0_USB_DVDD12 ; B = GND

(kicad_pcb
	(version 20260206)
	(generator "pcbnew")
	(generator_version "10.0")
	(general
		(thickness 1.6)
		(legacy_teardrops no)
	)
	(paper "A4")
	(title_block
		(title "04192023_DAF0TMB3IC0_F0TG_MB_C_brd_V02_OCP.brd")
		(comment 1 "Grand Teton / footprints 6435-6436 of 8354")
	)
	(layers
		(0 "F.Cu" signal "TOP")
		(4 "In1.Cu" signal "GND")
		(6 "In2.Cu" signal "IN1")
		(8 "In3.Cu" signal "GND1")
		(10 "In4.Cu" signal "IN2")
		(12 "In5.Cu" signal "GND2")
		(14 "In6.Cu" signal "IN3")
		(16 "In7.Cu" signal "GND3")
		(18 "In8.Cu" signal "VCC")
		(20 "In9.Cu" signal "VCC1")
		(22 "In10.Cu" signal "GND4")
		(24 "In11.Cu" signal "IN4")
		(26 "In12.Cu" signal "GND5")
		(28 "In13.Cu" signal "IN5")
		(30 "In14.Cu" signal "GND6")
		(32 "In15.Cu" signal "IN6")
		(34 "In16.Cu" signal "GND7")
		(2 "B.Cu" signal "BOTTOM")
		(9 "F.Adhes" user "F.Adhesive")
		(11 "B.Adhes" user "B.Adhesive")
		(13 "F.Paste" user "Package Geometry/Pastemask Top")
		(15 "B.Paste" user "Package Geometry/Pastemask Bottom")
		(5 "F.SilkS" user "Ref Des/Silkscreen Top")
		(7 "B.SilkS" user "Ref Des/Silkscreen Bottom")
		(1 "F.Mask" user "Board Geometry/Soldermask Top")
		(3 "B.Mask" user "Board Geometry/Soldermask Bottom")
		(17 "Dwgs.User" user "User.Drawings")
		(19 "Cmts.User" user "User.Comments")
		(21 "Eco1.User" user "User.Eco1")
		(23 "Eco2.User" user "User.Eco2")
		(25 "Edge.Cuts" user "Board Geometry/Outline")
		(27 "Margin" user)
		(31 "F.CrtYd" user "Package Geometry/Place Bound Top")
		(29 "B.CrtYd" user "Package Geometry/Place Bound Bottom")
		(35 "F.Fab" user "Ref Des/Assembly Top")
		(33 "B.Fab" user "Ref Des/Assembly Bottom")
	)
	(footprint ""
		(layer "B.Cu")
		(at 134.840218 -42.401998)
		(property "Reference" "C6031"
			(at 0 0 0)
			(layer "B.SilkS")
			(hide yes)
			(effects
				(font
					(size 1.27 1.27)
				)
				(justify mirror)
			)
		)
		(property "Value" ""
			(at 0 0 0)
			(layer "B.Fab")
			(effects
				(font
					(size 1.27 1.27)
				)
				(justify mirror)
			)
		)
		(duplicate_pad_numbers_are_jumpers no)
		(fp_line
			(start -0.7874 -0.4064)
			(end -0.7874 0.4064)
			(stroke
				(width 0.1524)
				(type default)
			)
			(layer "B.SilkS")
		)
		(fp_line
			(start -0.7874 0.4064)
			(end 0.7874 0.4064)
			(stroke
				(width 0.1524)
				(type default)
			)
			(layer "B.SilkS")
		)
		(fp_line
			(start 0.7874 -0.4064)
			(end -0.7874 -0.4064)
			(stroke
				(width 0.1524)
				(type default)
			)
			(layer "B.SilkS")
		)
		(fp_line
			(start 0.7874 0.4064)
			(end 0.7874 -0.4064)
			(stroke
				(width 0.1524)
				(type default)
			)
			(layer "B.SilkS")
		)
		(fp_line
			(start -0.67945 -0.3048)
			(end -0.67945 0.3048)
			(stroke
				(width 0.1)
				(type default)
			)
			(layer "B.Fab")
		)
		(fp_line
			(start -0.67945 0.3048)
			(end -0.120396 0.3048)
			(stroke
				(width 0.1)
				(type default)
			)
			(layer "B.Fab")
		)
		(fp_line
			(start -0.12065 -0.3048)
			(end -0.67945 -0.3048)
			(stroke
				(width 0.1)
				(type default)
			)
			(layer "B.Fab")
		)
		(fp_line
			(start -0.12065 -0.2794)
			(end -0.12065 -0.3048)
			(stroke
				(width 0.1)
				(type default)
			)
			(layer "B.Fab")
		)
		(fp_line
			(start -0.120396 0.2794)
			(end 0.12065 0.2794)
			(stroke
				(width 0.1)
				(type default)
			)
			(layer "B.Fab")
		)
		(fp_line
			(start -0.120396 0.3048)
			(end -0.120396 0.2794)
			(stroke
				(width 0.1)
				(type default)
			)
			(layer "B.Fab")
		)
		(fp_line
			(start 0.12065 -0.305054)
			(end 0.12065 -0.2794)
			(stroke
				(width 0.1)
				(type default)
			)
			(layer "B.Fab")
		)
		(fp_line
			(start 0.12065 -0.2794)
			(end -0.12065 -0.2794)
			(stroke
				(width 0.1)
				(type default)
			)
			(layer "B.Fab")
		)
		(fp_line
			(start 0.12065 0.2794)
			(end 0.12065 0.3048)
			(stroke
				(width 0.1)
				(type default)
			)
			(layer "B.Fab")
		)
		(fp_line
			(start 0.12065 0.3048)
			(end 0.67945 0.3048)
			(stroke
				(width 0.1)
				(type default)
			)
			(layer "B.Fab")
		)
		(fp_line
			(start 0.67945 -0.305054)
			(end 0.12065 -0.305054)
			(stroke
				(width 0.1)
				(type default)
			)
			(layer "B.Fab")
		)
		(fp_line
			(start 0.67945 0.3048)
			(end 0.67945 -0.305054)
			(stroke
				(width 0.1)
				(type default)
			)
			(layer "B.Fab")
		)
		(pad "1" smd circle
			(at 0.40005 0 180)
			(size 0 0)
			(layers "B.Cu" "B.Mask" "B.Paste")
			(net "P1V2_CPU0_USB_DVDD12")
		)
		(pad "2" smd circle
			(at -0.40005 0 180)
			(size 0 0)
			(layers "B.Cu" "B.Mask" "B.Paste")
			(net "GND")
		)
	)
	(footprint ""
		(layer "B.Cu")
		(at 170.307 -98.135948 -90)
		(property "Reference" "R6027"
			(at 0 0 90)
			(layer "B.SilkS")
			(hide yes)
			(effects
				(font
					(size 1.27 1.27)
				)
				(justify mirror)
			)
		)
		(property "Value" ""
			(at 0 0 90)
			(layer "B.Fab")
			(effects
				(font
					(size 1.27 1.27)
				)
				(justify mirror)
			)
		)
		(duplicate_pad_numbers_are_jumpers no)
		(fp_line
			(start -0.7874 0.4064)
			(end 0.7874 0.4064)
			(stroke
				(width 0.1524)
				(type default)
			)
			(layer "B.SilkS")
		)
		(fp_line
			(start 0.7874 0.4064)
			(end 0.7874 -0.4064)
			(stroke
				(width 0.1524)
				(type default)
			)
			(layer "B.SilkS")
		)
		(fp_line
			(start -0.7874 -0.4064)
			(end -0.7874 0.4064)
			(stroke
				(width 0.1524)
				(type default)
			)
			(layer "B.SilkS")
		)
		(fp_line
			(start 0.7874 -0.4064)
			(end -0.7874 -0.4064)
			(stroke
				(width 0.1524)
				(type default)
			)
			(layer "B.SilkS")
		)
		(fp_line
			(start -0.67945 0.3048)
			(end -0.120396 0.3048)
			(stroke
				(width 0.1)
				(type default)
			)
			(layer "B.Fab")
		)
		(fp_line
			(start -0.120396 0.3048)
			(end -0.120396 0.2794)
			(stroke
				(width 0.1)
				(type default)
			)
			(layer "B.Fab")
		)
		(fp_line
			(start 0.12065 0.3048)
			(end 0.67945 0.3048)
			(stroke
				(width 0.1)
				(type default)
			)
			(layer "B.Fab")
		)
		(fp_line
			(start 0.67945 0.3048)
			(end 0.67945 -0.305054)
			(stroke
				(width 0.1)
				(type default)
			)
			(layer "B.Fab")
		)
		(fp_line
			(start -0.120396 0.2794)
			(end 0.12065 0.2794)
			(stroke
				(width 0.1)
				(type default)
			)
			(layer "B.Fab")
		)
		(fp_line
			(start 0.12065 0.2794)
			(end 0.12065 0.3048)
			(stroke
				(width 0.1)
				(type default)
			)
			(layer "B.Fab")
		)
		(fp_line
			(start -0.12065 -0.2794)
			(end -0.12065 -0.3048)
			(stroke
				(width 0.1)
				(type default)
			)
			(layer "B.Fab")
		)
		(fp_line
			(start 0.12065 -0.2794)
			(end -0.12065 -0.2794)
			(stroke
				(width 0.1)
				(type default)
			)
			(layer "B.Fab")
		)
		(fp_line
			(start -0.67945 -0.3048)
			(end -0.67945 0.3048)
			(stroke
				(width 0.1)
				(type default)
			)
			(layer "B.Fab")
		)
		(fp_line
			(start -0.12065 -0.3048)
			(end -0.67945 -0.3048)
			(stroke
				(width 0.1)
				(type default)
			)
			(layer "B.Fab")
		)
		(fp_line
			(start 0.12065 -0.305054)
			(end 0.12065 -0.2794)
			(stroke
				(width 0.1)
				(type default)
			)
			(layer "B.Fab")
		)
		(fp_line
			(start 0.67945 -0.305054)
			(end 0.12065 -0.305054)
			(stroke
				(width 0.1)
				(type default)
			)
			(layer "B.Fab")
		)
		(pad "1" smd circle
			(at 0.40005 0 90)
			(size 0 0)
			(layers "B.Cu" "B.Mask" "B.Paste")
			(net "SGPIO_SCM_RESET_N")
		)
		(pad "2" smd circle
			(at -0.40005 0 90)
			(size 0 0)
			(layers "B.Cu" "B.Mask" "B.Paste")
			(net "GND")
		)
	)
)
